(kicad_pcb
	(version 20260206)
	(generator "pcbnew")
	(generator_version "10.0")
	(general
		(thickness 1.6)
		(legacy_teardrops no)
	)
	(paper "A4")
	(title_block
		(title "Bryce Canyon_IOM_IOC_16318-2_OCP.brd")
		(comment 1 "Bryce Canyon / footprints 118-122 of 1605")
	)
	(layers
		(0 "F.Cu" signal "TOP")
		(4 "In1.Cu" signal "L2GND")
		(6 "In2.Cu" signal "L3")
		(8 "In3.Cu" signal "L4VCC")
		(10 "In4.Cu" signal "L5VCC")
		(12 "In5.Cu" signal "L6")
		(14 "In6.Cu" signal "L7GND")
		(2 "B.Cu" signal "BOTTOM")
		(9 "F.Adhes" user "F.Adhesive")
		(11 "B.Adhes" user "B.Adhesive")
		(13 "F.Paste" user "Package Geometry/Pastemask Top")
		(15 "B.Paste" user "Package Geometry/Pastemask Bottom")
		(5 "F.SilkS" user "Ref Des/Silkscreen Top")
		(7 "B.SilkS" user "Ref Des/Silkscreen Bottom")
		(1 "F.Mask" user "Board Geometry/Soldermask Top")
		(3 "B.Mask" user "Board Geometry/Soldermask Bottom")
		(17 "Dwgs.User" user "User.Drawings")
		(19 "Cmts.User" user "User.Comments")
		(21 "Eco1.User" user "User.Eco1")
		(23 "Eco2.User" user "User.Eco2")
		(25 "Edge.Cuts" user "Board Geometry/Outline")
		(27 "Margin" user)
		(31 "F.CrtYd" user "Package Geometry/Place Bound Top")
		(29 "B.CrtYd" user "Package Geometry/Place Bound Bottom")
		(35 "F.Fab" user "Ref Des/Assembly Top")
		(33 "B.Fab" user "Ref Des/Assembly Bottom")
	)
	(footprint ""
		(layer "F.Cu")
		(at 182.9308 -124.714 180)
		(property "Reference" "C278"
			(at 0 0 180)
			(layer "F.SilkS")
			(hide yes)
			(effects
				(font
					(size 1.27 1.27)
				)
			)
		)
		(property "Value" "SC1U25V3KX-GP"
			(at 0 -2.8194 180)
			(unlocked yes)
			(layer "F.Fab")
			(hide yes)
			(effects
				(font
					(size 1.016 1.016)
					(thickness 0.1524)
				)
			)
		)
		(property "Device Type" "C603H36"
			(at 0 -4.3434 180)
			(unlocked yes)
			(layer "F.Fab")
			(hide yes)
			(effects
				(font
					(size 1.016 1.016)
					(thickness 0.1524)
				)
			)
		)
		(duplicate_pad_numbers_are_jumpers no)
		(fp_line
			(start 0.508 0)
			(end -0.508 0)
			(stroke
				(width 0.2032)
				(type default)
			)
			(layer "F.SilkS")
		)
		(fp_rect
			(start -0.5842 1.3335)
			(end 0.5842 -1.3335)
			(stroke
				(width 0)
				(type default)
			)
			(fill no)
			(layer "F.CrtYd")
		)
		(fp_rect
			(start -0.5842 1.3335)
			(end 0.5842 -1.3335)
			(stroke
				(width 0)
				(type default)
			)
			(fill no)
			(layer "F.Fab")
		)
		(pad "1" smd custom
			(at 0 -0.762 180)
			(size 0.2159 0.2159)
			(layers "F.Cu" "F.Mask" "F.Paste")
			(net "VT235_AVDD")
			(options
				(clearance outline)
				(anchor circle)
			)
			(primitives
				(gr_poly
					(pts
						(arc
							(start -0.3302 -0.4318)
							(mid -0.402042 -0.402042)
							(end -0.4318 -0.3302)
						)
						(arc
							(start -0.4318 0.3302)
							(mid -0.402042 0.402042)
							(end -0.3302 0.4318)
						)
						(arc
							(start 0.3302 0.4318)
							(mid 0.402042 0.402042)
							(end 0.4318 0.3302)
						)
						(arc
							(start 0.4318 -0.3302)
							(mid 0.402042 -0.402042)
							(end 0.3302 -0.4318)
						)
					)
					(width 0)
					(fill yes)
				)
			)
		)
		(pad "2" smd custom
			(at 0 0.762 180)
			(size 0.2159 0.2159)
			(layers "F.Cu" "F.Mask" "F.Paste")
			(net "AGND_P0V975")
			(options
				(clearance outline)
				(anchor circle)
			)
			(primitives
				(gr_poly
					(pts
						(arc
							(start -0.3302 -0.4318)
							(mid -0.402042 -0.402042)
							(end -0.4318 -0.3302)
						)
						(arc
							(start -0.4318 0.3302)
							(mid -0.402042 0.402042)
							(end -0.3302 0.4318)
						)
						(arc
							(start 0.3302 0.4318)
							(mid 0.402042 0.402042)
							(end 0.4318 0.3302)
						)
						(arc
							(start 0.4318 -0.3302)
							(mid 0.402042 -0.402042)
							(end 0.3302 -0.4318)
						)
					)
					(width 0)
					(fill yes)
				)
			)
		)
	)
	(footprint ""
		(layer "F.Cu")
		(at 118.872 -8.9916 90)
		(property "Reference" "U35"
			(at 0 0 90)
			(layer "F.SilkS")
			(hide yes)
			(effects
				(font
					(size 1.27 1.27)
				)
			)
		)
		(property "Value" "ADM1278-2ACPZ-RL-1-GP"
			(at -4.7625 -7.4422 90)
			(unlocked yes)
			(layer "F.Fab")
			(hide yes)
			(effects
				(font
					(size 1.016 1.016)
					(thickness 0.1524)
				)
			)
		)
		(property "Device Type" "QFN32-G3D45-UH32"
			(at -4.7625 -8.9662 90)
			(unlocked yes)
			(layer "F.Fab")
			(hide yes)
			(effects
				(font
					(size 1.016 1.016)
					(thickness 0.1524)
				)
			)
		)
		(duplicate_pad_numbers_are_jumpers no)
		(fp_line
			(start -0.250698 -3.7973)
			(end -0.250698 -3.2893)
			(stroke
				(width 0.1524)
				(type default)
			)
			(layer "F.SilkS")
		)
		(fp_line
			(start -3.5179 -3.5179)
			(end -2.2479 -3.5179)
			(stroke
				(width 0.1524)
				(type default)
			)
			(layer "F.SilkS")
		)
		(fp_line
			(start -3.5179 -2.2479)
			(end -3.5179 -3.5179)
			(stroke
				(width 0.1524)
				(type default)
			)
			(layer "F.SilkS")
		)
		(fp_line
			(start -4.0513 -1.24968)
			(end -3.2893 -1.24968)
			(stroke
				(width 0.1524)
				(type default)
			)
			(layer "F.SilkS")
		)
		(fp_line
			(start 4.0513 -0.749808)
			(end 3.2893 -0.749808)
			(stroke
				(width 0.1524)
				(type default)
			)
			(layer "F.SilkS")
		)
		(fp_line
			(start -3.7973 1.24968)
			(end -3.2893 1.24968)
			(stroke
				(width 0.1524)
				(type default)
			)
			(layer "F.SilkS")
		)
		(fp_line
			(start 3.7973 1.749552)
			(end 3.2893 1.749552)
			(stroke
				(width 0.1524)
				(type default)
			)
			(layer "F.SilkS")
		)
		(fp_line
			(start 3.5179 2.2479)
			(end 3.5179 3.5179)
			(stroke
				(width 0.1524)
				(type default)
			)
			(layer "F.SilkS")
		)
		(fp_line
			(start -3.5179 2.2479)
			(end -3.5179 3.5179)
			(stroke
				(width 0.1524)
				(type default)
			)
			(layer "F.SilkS")
		)
		(fp_line
			(start 3.5179 3.5179)
			(end 2.2479 3.5179)
			(stroke
				(width 0.1524)
				(type default)
			)
			(layer "F.SilkS")
		)
		(fp_line
			(start -3.5179 3.5179)
			(end -2.2479 3.5179)
			(stroke
				(width 0.1524)
				(type default)
			)
			(layer "F.SilkS")
		)
		(fp_line
			(start -0.250698 4.0513)
			(end -0.250698 3.2893)
			(stroke
				(width 0.1524)
				(type default)
			)
			(layer "F.SilkS")
		)
		(fp_poly
			(pts
				(xy 2.2479 -3.5179) (xy 3.5179 -2.2479) (xy 3.5179 -3.5179)
			)
			(stroke
				(width 0)
				(type default)
			)
			(fill yes)
			(layer "F.SilkS")
		)
		(fp_rect
			(start -2.5019 2.5019)
			(end 2.5019 -2.5019)
			(stroke
				(width 0)
				(type default)
			)
			(fill no)
			(layer "F.CrtYd")
		)
		(fp_poly
			(pts
				(xy -3.5179 3.5179) (xy -3.5179 -3.5179) (xy 3.5179 -3.5179) (xy 3.5179 3.5179) (xy -2.49682 3.5179)
				(xy -2.49682 2.5019) (xy 2.5019 2.5019) (xy 2.5019 -2.5019) (xy -2.5019 -2.5019) (xy -2.5019 3.5179)
			)
			(stroke
				(width 0)
				(type default)
			)
			(fill no)
			(layer "F.CrtYd")
		)
		(fp_rect
			(start -3.5179 3.5179)
			(end 3.5179 -3.5179)
			(stroke
				(width 0)
				(type default)
			)
			(fill no)
			(layer "F.Fab")
		)
		(pad "1" smd rect
			(at 1.75006 -2.5527 90)
			(size 0.3048 0.9144)
			(layers "F.Cu" "F.Mask" "F.Paste")
			(net "MB0_PSET_R")
		)
		(pad "2" smd rect
			(at 1.249934 -2.4765 90)
			(size 0.3048 1.0668)
			(layers "F.Cu" "F.Mask" "F.Paste")
			(net "MB0_VCAP_R")
		)
		(pad "3" smd rect
			(at 0.750062 -2.4765 90)
			(size 0.3048 1.0668)
			(layers "F.Cu" "F.Mask" "F.Paste")
			(net "MB0_ISET_R")
		)
		(pad "4" smd rect
			(at 0.249936 -2.4765 90)
			(size 0.3048 1.0668)
			(layers "F.Cu" "F.Mask" "F.Paste")
			(net "MB0_ISTART_R")
		)
		(pad "5" smd rect
			(at -0.249936 -2.4765 90)
			(size 0.3048 1.0668)
			(layers "F.Cu" "F.Mask" "F.Paste")
			(net "MB0_TIME_R")
		)
		(pad "6" smd rect
			(at -0.750062 -2.4765 90)
			(size 0.3048 1.0668)
			(layers "F.Cu" "F.Mask" "F.Paste")
			(net "Net_320")
		)
		(pad "7" smd rect
			(at -1.249934 -2.4765 90)
			(size 0.3048 1.0668)
			(layers "F.Cu" "F.Mask" "F.Paste")
			(net "MB0_CM_ADR1_R")
		)
		(pad "8" smd rect
			(at -1.75006 -2.5527 90)
			(size 0.3048 0.9144)
			(layers "F.Cu" "F.Mask" "F.Paste")
			(net "MB0_CM_ADR2_R")
		)
		(pad "9" smd rect
			(at -2.5527 -1.75006 90)
			(size 0.9144 0.3048)
			(layers "F.Cu" "F.Mask" "F.Paste")
			(net "MB0_SPISS_PD")
		)
		(pad "10" smd rect
			(at -2.4765 -1.249934 90)
			(size 1.0668 0.3048)
			(layers "F.Cu" "F.Mask" "F.Paste")
			(net "Net_324")
		)
		(pad "11" smd rect
			(at -2.4765 -0.750062 90)
			(size 1.0668 0.3048)
			(layers "F.Cu" "F.Mask" "F.Paste")
			(net "Net_323")
		)
		(pad "12" smd rect
			(at -2.4765 -0.249936 90)
			(size 1.0668 0.3048)
			(layers "F.Cu" "F.Mask" "F.Paste")
			(net "MB0_HS_ENABLE")
		)
		(pad "13" smd rect
			(at -2.4765 0.249936 90)
			(size 1.0668 0.3048)
			(layers "F.Cu" "F.Mask" "F.Paste")
			(net "Net_322")
		)
		(pad "14" smd rect
			(at -2.4765 0.750062 90)
			(size 1.0668 0.3048)
			(layers "F.Cu" "F.Mask" "F.Paste")
			(net "Net_321")
		)
		(pad "15" smd rect
			(at -2.4765 1.249934 90)
			(size 1.0668 0.3048)
			(layers "F.Cu" "F.Mask" "F.Paste")
			(net "HSW_SDA")
		)
		(pad "16" smd rect
			(at -2.5527 1.75006 90)
			(size 0.9144 0.3048)
			(layers "F.Cu" "F.Mask" "F.Paste")
			(net "HSW_SCL")
		)
		(pad "17" smd rect
			(at -1.75006 2.5527 90)
			(size 0.3048 0.9144)
			(layers "F.Cu" "F.Mask" "F.Paste")
			(net "MB0_RETRY_R")
		)
		(pad "18" smd rect
			(at -1.249934 2.4765 90)
			(size 0.3048 1.0668)
			(layers "F.Cu" "F.Mask" "F.Paste")
			(net "P12V_IOM_PGOOD")
		)
		(pad "19" smd rect
			(at -0.750062 2.4765 90)
			(size 0.3048 1.0668)
			(layers "F.Cu" "F.Mask" "F.Paste")
			(net "Net_325")
		)
		(pad "20" smd rect
			(at -0.249936 2.4765 90)
			(size 0.3048 1.0668)
			(layers "F.Cu" "F.Mask" "F.Paste")
			(net "MB0_CM_VOUT_R")
		)
		(pad "21" smd rect
			(at 0.249936 2.4765 90)
			(size 0.3048 1.0668)
			(layers "F.Cu" "F.Mask" "F.Paste")
			(net "MB0_P12V_PWGIN_R")
		)
		(pad "22" smd rect
			(at 0.750062 2.4765 90)
			(size 0.3048 1.0668)
			(layers "F.Cu" "F.Mask" "F.Paste")
			(net "AGND_CURRENT_MON")
		)
		(pad "23" smd rect
			(at 1.249934 2.4765 90)
			(size 0.3048 1.0668)
			(layers "F.Cu" "F.Mask" "F.Paste")
			(net "GND")
		)
		(pad "24" smd rect
			(at 1.75006 2.5527 90)
			(size 0.3048 0.9144)
			(layers "F.Cu" "F.Mask" "F.Paste")
			(net "MB0_CM_GATE")
		)
		(pad "25" smd rect
			(at 2.5527 1.75006 90)
			(size 0.9144 0.3048)
			(layers "F.Cu" "F.Mask" "F.Paste")
			(net "MB0_TEMP")
		)
		(pad "26" smd rect
			(at 2.4765 1.249934 90)
			(size 1.0668 0.3048)
			(layers "F.Cu" "F.Mask" "F.Paste")
			(net "MB0_CM_SENSE_N")
		)
		(pad "27" smd rect
			(at 2.4765 0.750062 90)
			(size 1.0668 0.3048)
			(layers "F.Cu" "F.Mask" "F.Paste")
			(net "ADM1278_HS_N")
		)
		(pad "28" smd rect
			(at 2.4765 0.249936 90)
			(size 1.0668 0.3048)
			(layers "F.Cu" "F.Mask" "F.Paste")
			(net "ADM1278_HS_P")
		)
		(pad "29" smd rect
			(at 2.4765 -0.249936 90)
			(size 1.0668 0.3048)
			(layers "F.Cu" "F.Mask" "F.Paste")
			(net "MB0_CM_SENSE_P")
		)
		(pad "30" smd rect
			(at 2.4765 -0.750062 90)
			(size 1.0668 0.3048)
			(layers "F.Cu" "F.Mask" "F.Paste")
			(net "MB0_VCC")
		)
		(pad "31" smd rect
			(at 2.4765 -1.249934 90)
			(size 1.0668 0.3048)
			(layers "F.Cu" "F.Mask" "F.Paste")
			(net "MB0_CM_UV_R")
		)
		(pad "32" smd rect
			(at 2.5527 -1.75006 90)
			(size 0.9144 0.3048)
			(layers "F.Cu" "F.Mask" "F.Paste")
			(net "MB0_CM_OV_R")
		)
		(pad "33" smd rect
			(at 0 0 90)
			(size 3.4544 3.4544)
			(layers "F.Cu" "F.Mask" "F.Paste")
			(net "AGND_CURRENT_MON")
		)
	)
	(footprint ""
		(layer "F.Cu")
		(at 12.6746 -170.988736)
		(property "Reference" "C233"
			(at 0 0 0)
			(layer "F.SilkS")
			(hide yes)
			(effects
				(font
					(size 1.27 1.27)
				)
			)
		)
		(property "Value" "SCD1U16V2KX-3GP"
			(at 1.1811 -2.7051 0)
			(unlocked yes)
			(layer "F.Fab")
			(hide yes)
			(effects
				(font
					(size 1.016 1.016)
					(thickness 0.1524)
				)
			)
		)
		(property "Device Type" "C402H22"
			(at 1.1811 -4.2291 0)
			(unlocked yes)
			(layer "F.Fab")
			(hide yes)
			(effects
				(font
					(size 1.016 1.016)
					(thickness 0.1524)
				)
			)
		)
		(duplicate_pad_numbers_are_jumpers no)
		(fp_rect
			(start -0.4318 0.9525)
			(end 0.4318 -0.9525)
			(stroke
				(width 0)
				(type default)
			)
			(fill no)
			(layer "F.CrtYd")
		)
		(fp_rect
			(start -0.4318 0.9525)
			(end 0.4318 -0.9525)
			(stroke
				(width 0)
				(type default)
			)
			(fill no)
			(layer "F.Fab")
		)
		(pad "1" smd custom
			(at 0 -0.4445)
			(size 0.1524 0.1524)
			(layers "F.Cu" "F.Mask" "F.Paste")
			(net "TPS74801_P1V2_STBY_EN")
			(options
				(clearance outline)
				(anchor circle)
			)
			(primitives
				(gr_poly
					(pts
						(arc
							(start 0.3048 -0.2032)
							(mid 0.275042 -0.275042)
							(end 0.2032 -0.3048)
						)
						(arc
							(start -0.2032 -0.3048)
							(mid -0.275042 -0.275042)
							(end -0.3048 -0.2032)
						)
						(arc
							(start -0.3048 0.2032)
							(mid -0.275042 0.275042)
							(end -0.2032 0.3048)
						)
						(arc
							(start 0.2032 0.3048)
							(mid 0.275042 0.275042)
							(end 0.3048 0.2032)
						)
					)
					(width 0)
					(fill yes)
				)
			)
		)
		(pad "2" smd custom
			(at 0 0.4445)
			(size 0.1524 0.1524)
			(layers "F.Cu" "F.Mask" "F.Paste")
			(net "GND")
			(options
				(clearance outline)
				(anchor circle)
			)
			(primitives
				(gr_poly
					(pts
						(arc
							(start 0.3048 -0.2032)
							(mid 0.275042 -0.275042)
							(end 0.2032 -0.3048)
						)
						(arc
							(start -0.2032 -0.3048)
							(mid -0.275042 -0.275042)
							(end -0.3048 -0.2032)
						)
						(arc
							(start -0.3048 0.2032)
							(mid -0.275042 0.275042)
							(end -0.2032 0.3048)
						)
						(arc
							(start 0.2032 0.3048)
							(mid 0.275042 0.275042)
							(end 0.3048 0.2032)
						)
					)
					(width 0)
					(fill yes)
				)
			)
		)
	)
	(footprint ""
		(layer "F.Cu")
		(at 88.9 -134.7978)
		(property "Reference" "R137"
			(at 0 0 0)
			(layer "F.SilkS")
			(hide yes)
			(effects
				(font
					(size 1.27 1.27)
				)
			)
		)
		(property "Value" "8K2R2J-3-GP"
			(at 0.064008 -3.993896 0)
			(unlocked yes)
			(layer "F.Fab")
			(hide yes)
			(effects
				(font
					(size 1.016 1.016)
					(thickness 0.1524)
				)
			)
		)
		(property "Device Type" "R402H16"
			(at 0.064008 -5.517896 0)
			(unlocked yes)
			(layer "F.Fab")
			(hide yes)
			(effects
				(font
					(size 1.016 1.016)
					(thickness 0.1524)
				)
			)
		)
		(duplicate_pad_numbers_are_jumpers no)
		(fp_line
			(start -0.508 -0.9398)
			(end -0.508 0.9398)
			(stroke
				(width 0.1524)
				(type default)
			)
			(layer "F.SilkS")
		)
		(fp_line
			(start 0.508 -0.9398)
			(end -0.508 -0.9398)
			(stroke
				(width 0.1524)
				(type default)
			)
			(layer "F.SilkS")
		)
		(fp_rect
			(start -0.508 0.9398)
			(end 0.508 -0.9398)
			(stroke
				(width 0)
				(type default)
			)
			(fill no)
			(layer "F.CrtYd")
		)
		(fp_rect
			(start -0.508 0.9398)
			(end 0.508 -0.9398)
			(stroke
				(width 0)
				(type default)
			)
			(fill no)
			(layer "F.Fab")
		)
		(pad "1" smd custom
			(at 0 -0.4445)
			(size 0.1397 0.1397)
			(layers "F.Cu" "F.Mask" "F.Paste")
			(net "EEPROM_A1")
			(options
				(clearance outline)
				(anchor circle)
			)
			(primitives
				(gr_poly
					(pts
						(arc
							(start -0.1778 -0.2794)
							(mid -0.249642 -0.249642)
							(end -0.2794 -0.1778)
						)
						(arc
							(start -0.2794 0.1778)
							(mid -0.249642 0.249642)
							(end -0.1778 0.2794)
						)
						(arc
							(start 0.1778 0.2794)
							(mid 0.249642 0.249642)
							(end 0.2794 0.1778)
						)
						(arc
							(start 0.2794 -0.1778)
							(mid 0.249642 -0.249642)
							(end 0.1778 -0.2794)
						)
					)
					(width 0)
					(fill yes)
				)
			)
		)
		(pad "2" smd custom
			(at 0 0.4445)
			(size 0.1397 0.1397)
			(layers "F.Cu" "F.Mask" "F.Paste")
			(net "GND")
			(options
				(clearance outline)
				(anchor circle)
			)
			(primitives
				(gr_poly
					(pts
						(arc
							(start -0.1778 -0.2794)
							(mid -0.249642 -0.249642)
							(end -0.2794 -0.1778)
						)
						(arc
							(start -0.2794 0.1778)
							(mid -0.249642 0.249642)
							(end -0.1778 0.2794)
						)
						(arc
							(start 0.1778 0.2794)
							(mid 0.249642 0.249642)
							(end 0.2794 0.1778)
						)
						(arc
							(start 0.2794 -0.1778)
							(mid 0.249642 -0.249642)
							(end 0.1778 -0.2794)
						)
					)
					(width 0)
					(fill yes)
				)
			)
		)
	)
	(footprint ""
		(layer "F.Cu")
		(at 200.8124 -48.2854 180)
		(property "Reference" "R634"
			(at 0 0 180)
			(layer "F.SilkS")
			(hide yes)
			(effects
				(font
					(size 1.27 1.27)
				)
			)
		)
		(property "Value" "4K7R2F-GP"
			(at 0.064008 -3.993896 180)
			(unlocked yes)
			(layer "F.Fab")
			(hide yes)
			(effects
				(font
					(size 1.016 1.016)
					(thickness 0.1524)
				)
			)
		)
		(property "Device Type" "R402H16"
			(at 0.064008 -5.517896 180)
			(unlocked yes)
			(layer "F.Fab")
			(hide yes)
			(effects
				(font
					(size 1.016 1.016)
					(thickness 0.1524)
				)
			)
		)
		(duplicate_pad_numbers_are_jumpers no)
		(fp_line
			(start 0.508 -0.9398)
			(end -0.508 -0.9398)
			(stroke
				(width 0.1524)
				(type default)
			)
			(layer "F.SilkS")
		)
		(fp_line
			(start -0.508 -0.9398)
			(end -0.508 0.9398)
			(stroke
				(width 0.1524)
				(type default)
			)
			(layer "F.SilkS")
		)
		(fp_rect
			(start -0.508 0.9398)
			(end 0.508 -0.9398)
			(stroke
				(width 0)
				(type default)
			)
			(fill no)
			(layer "F.CrtYd")
		)
		(fp_rect
			(start -0.508 0.9398)
			(end 0.508 -0.9398)
			(stroke
				(width 0)
				(type default)
			)
			(fill no)
			(layer "F.Fab")
		)
		(pad "1" smd custom
			(at 0 -0.4445 180)
			(size 0.1397 0.1397)
			(layers "F.Cu" "F.Mask" "F.Paste")
			(net "P1V8")
			(options
				(clearance outline)
				(anchor circle)
			)
			(primitives
				(gr_poly
					(pts
						(arc
							(start -0.1778 -0.2794)
							(mid -0.249642 -0.249642)
							(end -0.2794 -0.1778)
						)
						(arc
							(start -0.2794 0.1778)
							(mid -0.249642 0.249642)
							(end -0.1778 0.2794)
						)
						(arc
							(start 0.1778 0.2794)
							(mid 0.249642 0.249642)
							(end 0.2794 0.1778)
						)
						(arc
							(start 0.2794 -0.1778)
							(mid 0.249642 -0.249642)
							(end 0.1778 -0.2794)
						)
					)
					(width 0)
					(fill yes)
				)
			)
		)
		(pad "2" smd custom
			(at 0 0.4445 180)
			(size 0.1397 0.1397)
			(layers "F.Cu" "F.Mask" "F.Paste")
			(net "ICE0_TDI")
			(options
				(clearance outline)
				(anchor circle)
			)
			(primitives
				(gr_poly
					(pts
						(arc
							(start -0.1778 -0.2794)
							(mid -0.249642 -0.249642)
							(end -0.2794 -0.1778)
						)
						(arc
							(start -0.2794 0.1778)
							(mid -0.249642 0.249642)
							(end -0.1778 0.2794)
						)
						(arc
							(start 0.1778 0.2794)
							(mid 0.249642 0.249642)
							(end 0.2794 0.1778)
						)
						(arc
							(start 0.2794 -0.1778)
							(mid 0.249642 -0.249642)
							(end 0.1778 -0.2794)
						)
					)
					(width 0)
					(fill yes)
				)
			)
		)
	)
)
